# BASEBOARD_FAB2 (Tioga Pass) — schematic netlist excerpt (pin names and nets, part order shuffled) for the footprints in the layout excerpt that follows; sources: Cadence DE-HDL packaged netlist, KiCad conversion of Wiwynn_Tioga_Pass_MB.brd

C1D7  CAP  1.0UF 16V 10% X6S  pkg 0402  page 208 : A = VR_PVCCIN_CPU1_PH4_VCIN ; B = GND
L7G1  IND-120NH-30-GP  pkg DISCRET-GB2  page 216 : S = VR_PVDDQ_ABC_PH1_SW ; F = PVDDQ_ABC

Q9A3  FET_N  2N7002 FET  pkg SOT23LF  page 175
  GATE  = FM_BIOS_TOP_SWAP_SPKR
  SRC  = GND
  DRN  = FM_SPEAKER_PCH_N

(kicad_pcb
	(version 20260206)
	(generator "pcbnew")
	(generator_version "10.0")
	(general
		(thickness 1.6)
		(legacy_teardrops no)
	)
	(paper "A4")
	(title_block
		(title "Wiwynn_Tioga_Pass_MB.brd")
		(comment 1 "Tioga Pass / footprints 262-264 of 4770")
	)
	(layers
		(0 "F.Cu" signal "TOP")
		(4 "In1.Cu" signal "L2GND")
		(6 "In2.Cu" signal "L3")
		(8 "In3.Cu" signal "L4GND")
		(10 "In4.Cu" signal "L5")
		(12 "In5.Cu" signal "L6GND")
		(14 "In6.Cu" signal "L7VCC")
		(16 "In7.Cu" signal "L8VCC")
		(18 "In8.Cu" signal "L9GND")
		(20 "In9.Cu" signal "L10")
		(22 "In10.Cu" signal "L11GND")
		(24 "In11.Cu" signal "L12")
		(26 "In12.Cu" signal "L13GND")
		(2 "B.Cu" signal "BOTTOM")
		(9 "F.Adhes" user "F.Adhesive")
		(11 "B.Adhes" user "B.Adhesive")
		(13 "F.Paste" user "Package Geometry/Pastemask Top")
		(15 "B.Paste" user "Package Geometry/Pastemask Bottom")
		(5 "F.SilkS" user "Ref Des/Silkscreen Top")
		(7 "B.SilkS" user "Ref Des/Silkscreen Bottom")
		(1 "F.Mask" user "Board Geometry/Soldermask Top")
		(3 "B.Mask" user "Board Geometry/Soldermask Bottom")
		(17 "Dwgs.User" user "User.Drawings")
		(19 "Cmts.User" user "User.Comments")
		(21 "Eco1.User" user "User.Eco1")
		(23 "Eco2.User" user "User.Eco2")
		(25 "Edge.Cuts" user "Board Geometry/Outline")
		(27 "Margin" user)
		(31 "F.CrtYd" user "Package Geometry/Place Bound Top")
		(29 "B.CrtYd" user "Package Geometry/Place Bound Bottom")
		(35 "F.Fab" user "Ref Des/Assembly Top")
		(33 "B.Fab" user "Ref Des/Assembly Bottom")
	)
	(footprint ""
		(layer "F.Cu")
		(at 340.872064 -5.746496 180)
		(property "Reference" "L7G1"
			(at 3.378708 -4.251706 180)
			(unlocked yes)
			(layer "F.SilkS")
			(effects
				(font
					(size 0.4064 0.254)
					(thickness 0.1524)
				)
			)
		)
		(property "Value" ""
			(at 0 0 180)
			(layer "F.Fab")
			(effects
				(font
					(size 1.27 1.27)
				)
			)
		)
		(duplicate_pad_numbers_are_jumpers no)
		(fp_line
			(start 8.3693 3.199892)
			(end -1.1303 3.199892)
			(stroke
				(width 0.1524)
				(type default)
			)
			(layer "F.SilkS")
		)
		(fp_line
			(start 8.3693 1.6637)
			(end 8.3693 3.199892)
			(stroke
				(width 0.1524)
				(type default)
			)
			(layer "F.SilkS")
		)
		(fp_line
			(start 8.3693 -3.199892)
			(end 8.3693 -1.6637)
			(stroke
				(width 0.1524)
				(type default)
			)
			(layer "F.SilkS")
		)
		(fp_line
			(start -1.1303 3.199892)
			(end -1.1303 1.6637)
			(stroke
				(width 0.1524)
				(type default)
			)
			(layer "F.SilkS")
		)
		(fp_line
			(start -1.1303 -1.6637)
			(end -1.1303 -3.199892)
			(stroke
				(width 0.1524)
				(type default)
			)
			(layer "F.SilkS")
		)
		(fp_line
			(start -1.1303 -3.199892)
			(end 8.3693 -3.199892)
			(stroke
				(width 0.1524)
				(type default)
			)
			(layer "F.SilkS")
		)
		(fp_rect
			(start -1.1303 3.199892)
			(end 8.3693 -3.199892)
			(stroke
				(width 0)
				(type default)
			)
			(fill no)
			(layer "F.CrtYd")
		)
		(fp_line
			(start 8.3693 3.199892)
			(end -1.1303 3.199892)
			(stroke
				(width 0.1)
				(type default)
			)
			(layer "F.Fab")
		)
		(fp_line
			(start 8.3693 -3.199892)
			(end 8.3693 3.199892)
			(stroke
				(width 0.1)
				(type default)
			)
			(layer "F.Fab")
		)
		(fp_line
			(start -1.1303 3.199892)
			(end -1.1303 -3.199892)
			(stroke
				(width 0.1)
				(type default)
			)
			(layer "F.Fab")
		)
		(fp_line
			(start -1.1303 -3.199892)
			(end 8.3693 -3.199892)
			(stroke
				(width 0.1)
				(type default)
			)
			(layer "F.Fab")
		)
		(pad "1" smd rect
			(at 0 0 180)
			(size 3.683 2.667)
			(layers "F.Cu" "F.Mask" "F.Paste")
			(net "VR_PVDDQ_ABC_PH1_SW")
		)
		(pad "2" smd rect
			(at 7.239 0 180)
			(size 3.683 2.667)
			(layers "F.Cu" "F.Mask" "F.Paste")
			(net "PVDDQ_ABC")
		)
	)
	(footprint ""
		(layer "F.Cu")
		(at 489.204 -137.16 90)
		(property "Reference" "Q9A3"
			(at -0.88265 0.0254 0)
			(unlocked yes)
			(layer "F.SilkS")
			(effects
				(font
					(size 0.7874 0.5842)
					(thickness 0.1524)
				)
				(justify left)
			)
		)
		(property "Value" ""
			(at 0 0 90)
			(layer "F.Fab")
			(effects
				(font
					(size 1.27 1.27)
				)
			)
		)
		(duplicate_pad_numbers_are_jumpers no)
		(fp_line
			(start 1.778 -0.5715)
			(end 1.778 0.3175)
			(stroke
				(width 0.1524)
				(type default)
			)
			(layer "F.SilkS")
		)
		(fp_line
			(start 0.9525 -0.5715)
			(end 1.778 -0.5715)
			(stroke
				(width 0.1524)
				(type default)
			)
			(layer "F.SilkS")
		)
		(fp_line
			(start 0.381 0.635)
			(end 0.381 1.27)
			(stroke
				(width 0.1524)
				(type default)
			)
			(layer "F.SilkS")
		)
		(fp_line
			(start 1.778 2.4765)
			(end 1.778 1.5875)
			(stroke
				(width 0.1524)
				(type default)
			)
			(layer "F.SilkS")
		)
		(fp_line
			(start 0.9525 2.4765)
			(end 1.778 2.4765)
			(stroke
				(width 0.1524)
				(type default)
			)
			(layer "F.SilkS")
		)
		(fp_circle
			(center -0.9525 -0.9271)
			(end -0.9525 -0.8001)
			(stroke
				(width 0.254)
				(type default)
			)
			(fill no)
			(layer "F.SilkS")
		)
		(fp_poly
			(pts
				(xy 1.778 2.4765) (xy 0.381 2.4765) (xy 0.381 -0.5715) (xy 1.778 -0.5715)
			)
			(stroke
				(width 0)
				(type default)
			)
			(fill no)
			(layer "F.CrtYd")
		)
		(fp_line
			(start 1.778 -0.5715)
			(end 0.381 -0.5715)
			(stroke
				(width 0.1)
				(type default)
			)
			(layer "F.Fab")
		)
		(fp_line
			(start 0.381 -0.5715)
			(end 0.381 2.4765)
			(stroke
				(width 0.1)
				(type default)
			)
			(layer "F.Fab")
		)
		(fp_line
			(start 1.778 2.4765)
			(end 1.778 -0.5715)
			(stroke
				(width 0.1)
				(type default)
			)
			(layer "F.Fab")
		)
		(fp_line
			(start 0.381 2.4765)
			(end 1.778 2.4765)
			(stroke
				(width 0.1)
				(type default)
			)
			(layer "F.Fab")
		)
		(fp_circle
			(center -0.9525 -0.9271)
			(end -0.9525 -0.8001)
			(stroke
				(width 0.254)
				(type default)
			)
			(fill no)
			(layer "F.Fab")
		)
		(pad "1" smd rect
			(at 0 0 90)
			(size 1.143 0.508)
			(layers "F.Cu" "F.Mask" "F.Paste")
			(net "FM_BIOS_TOP_SWAP_SPKR")
		)
		(pad "2" smd rect
			(at 0 1.905 90)
			(size 1.143 0.508)
			(layers "F.Cu" "F.Mask" "F.Paste")
			(net "GND")
		)
		(pad "3" smd rect
			(at 2.159 0.9525 90)
			(size 1.143 0.508)
			(layers "F.Cu" "F.Mask" "F.Paste")
			(net "FM_SPEAKER_PCH_N")
		)
	)
	(footprint ""
		(layer "F.Cu")
		(at 32.289496 -77.351382 -90)
		(property "Reference" "C1D7"
			(at 0 0 270)
			(layer "F.SilkS")
			(hide yes)
			(effects
				(font
					(size 1.27 1.27)
				)
			)
		)
		(property "Value" ""
			(at 0 0 270)
			(layer "F.Fab")
			(effects
				(font
					(size 1.27 1.27)
				)
			)
		)
		(duplicate_pad_numbers_are_jumpers no)
		(fp_rect
			(start 0.3048 0.9906)
			(end -0.3048 -0.1016)
			(stroke
				(width 0)
				(type default)
			)
			(fill no)
			(layer "F.CrtYd")
		)
		(fp_line
			(start -0.3048 0.9906)
			(end 0.3048 0.9906)
			(stroke
				(width 0.1)
				(type default)
			)
			(layer "F.Fab")
		)
		(fp_line
			(start 0.3048 0.9906)
			(end 0.3048 -0.1016)
			(stroke
				(width 0.1)
				(type default)
			)
			(layer "F.Fab")
		)
		(fp_line
			(start -0.3048 -0.1016)
			(end -0.3048 0.9906)
			(stroke
				(width 0.1)
				(type default)
			)
			(layer "F.Fab")
		)
		(fp_line
			(start 0.3048 -0.1016)
			(end -0.3048 -0.1016)
			(stroke
				(width 0.1)
				(type default)
			)
			(layer "F.Fab")
		)
		(pad "1" smd rect
			(at 0 0 270)
			(size 0.508 0.508)
			(layers "F.Cu" "F.Mask" "F.Paste")
			(net "VR_PVCCIN_CPU1_PH4_VCIN")
		)
		(pad "2" smd rect
			(at 0 0.889 270)
			(size 0.508 0.508)
			(layers "F.Cu" "F.Mask" "F.Paste")
			(net "GND")
		)
		(zone
			(layer "F.Cu")
			(hatch none 0.5)
			(connect_pads
				(clearance 0)
			)
			(min_thickness 0.25)
			(keepout
				(tracks not_allowed)
				(vias allowed)
				(pads allowed)
				(copperpour not_allowed)
				(footprints allowed)
			)
			(placement
				(enabled no)
				(sheetname "")
			)
			(fill
				(thermal_gap 0.5)
				(thermal_bridge_width 0.5)
				(island_removal_mode 0)
			)
			(polygon
				(pts
					(xy 31.654496 -77.097382) (xy 32.035496 -77.097382) (xy 32.035496 -77.605382) (xy 31.654496 -77.605382)
				)
			)
		)
		(zone
			(layer "F.Cu")
			(hatch none 0.5)
			(connect_pads
				(clearance 0)
			)
			(min_thickness 0.25)
			(keepout
				(tracks allowed)
				(vias not_allowed)
				(pads allowed)
				(copperpour not_allowed)
				(footprints allowed)
			)
			(placement
				(enabled no)
				(sheetname "")
			)
			(fill
				(thermal_gap 0.5)
				(thermal_bridge_width 0.5)
				(island_removal_mode 0)
			)
			(polygon
				(pts
					(xy 31.654496 -77.097382) (xy 32.035496 -77.097382) (xy 32.035496 -77.605382) (xy 31.654496 -77.605382)
				)
			)
		)
	)
)
